# S9S_MB_2U (Grand Teton) — schematic netlist excerpt (pin names and nets, part order shuffled) for the footprints in the layout excerpt that follows; sources: Cadence DE-HDL packaged netlist, KiCad conversion of 03242023_DA0F0TMBIJ0_F0T_Motherboard_J_brd_V01_OCP.brd

C552  Q_CAP  0.1UF 25V 10% X7R  pkg 0402  page 131 : A = FM_CPU_FBRK_DEBUG_N ; B = GND
R727  Q_RES  10K 1% CHIP  pkg 0402LF  page 183 : A = PU_OC4_USB_N ; B = P3V3_AUX

(kicad_pcb
	(version 20260206)
	(generator "pcbnew")
	(generator_version "10.0")
	(general
		(thickness 1.6)
		(legacy_teardrops no)
	)
	(paper "A4")
	(title_block
		(title "03242023_DA0F0TMBIJ0_F0T_Motherboard_J_brd_V01_OCP.brd")
		(comment 1 "Grand Teton / footprints 1511-1512 of 6105")
	)
	(layers
		(0 "F.Cu" signal "TOP")
		(4 "In1.Cu" signal "GND")
		(6 "In2.Cu" signal "IN1")
		(8 "In3.Cu" signal "GND1")
		(10 "In4.Cu" signal "IN2")
		(12 "In5.Cu" signal "GND2")
		(14 "In6.Cu" signal "IN3")
		(16 "In7.Cu" signal "GND3")
		(18 "In8.Cu" signal "VCC")
		(20 "In9.Cu" signal "VCC1")
		(22 "In10.Cu" signal "GND4")
		(24 "In11.Cu" signal "IN4")
		(26 "In12.Cu" signal "GND5")
		(28 "In13.Cu" signal "IN5")
		(30 "In14.Cu" signal "GND6")
		(32 "In15.Cu" signal "IN6")
		(34 "In16.Cu" signal "GND7")
		(2 "B.Cu" signal "BOTTOM")
		(9 "F.Adhes" user "F.Adhesive")
		(11 "B.Adhes" user "B.Adhesive")
		(13 "F.Paste" user "Package Geometry/Pastemask Top")
		(15 "B.Paste" user "Package Geometry/Pastemask Bottom")
		(5 "F.SilkS" user "Ref Des/Silkscreen Top")
		(7 "B.SilkS" user "Ref Des/Silkscreen Bottom")
		(1 "F.Mask" user "Board Geometry/Soldermask Top")
		(3 "B.Mask" user "Board Geometry/Soldermask Bottom")
		(17 "Dwgs.User" user "User.Drawings")
		(19 "Cmts.User" user "User.Comments")
		(21 "Eco1.User" user "User.Eco1")
		(23 "Eco2.User" user "User.Eco2")
		(25 "Edge.Cuts" user "Board Geometry/Outline")
		(27 "Margin" user)
		(31 "F.CrtYd" user "Package Geometry/Place Bound Top")
		(29 "B.CrtYd" user "Package Geometry/Place Bound Bottom")
		(35 "F.Fab" user "Ref Des/Assembly Top")
		(33 "B.Fab" user "Ref Des/Assembly Bottom")
	)
	(footprint ""
		(layer "F.Cu")
		(at 404.006812 -55.759604)
		(property "Reference" "C552"
			(at 0 0 0)
			(layer "F.SilkS")
			(hide yes)
			(effects
				(font
					(size 1.27 1.27)
				)
			)
		)
		(property "Value" ""
			(at 0 0 0)
			(layer "F.Fab")
			(effects
				(font
					(size 1.27 1.27)
				)
			)
		)
		(duplicate_pad_numbers_are_jumpers no)
		(fp_line
			(start -0.7874 -0.4064)
			(end 0.7874 -0.4064)
			(stroke
				(width 0.1524)
				(type default)
			)
			(layer "F.SilkS")
		)
		(fp_line
			(start -0.7874 0.4064)
			(end -0.7874 -0.4064)
			(stroke
				(width 0.1524)
				(type default)
			)
			(layer "F.SilkS")
		)
		(fp_line
			(start 0.7874 -0.4064)
			(end 0.7874 0.4064)
			(stroke
				(width 0.1524)
				(type default)
			)
			(layer "F.SilkS")
		)
		(fp_line
			(start 0.7874 0.4064)
			(end -0.7874 0.4064)
			(stroke
				(width 0.1524)
				(type default)
			)
			(layer "F.SilkS")
		)
		(fp_line
			(start -0.67945 -0.305054)
			(end -0.12065 -0.305054)
			(stroke
				(width 0.1)
				(type default)
			)
			(layer "F.Fab")
		)
		(fp_line
			(start -0.67945 0.3048)
			(end -0.67945 -0.305054)
			(stroke
				(width 0.1)
				(type default)
			)
			(layer "F.Fab")
		)
		(fp_line
			(start -0.12065 -0.305054)
			(end -0.12065 -0.2794)
			(stroke
				(width 0.1)
				(type default)
			)
			(layer "F.Fab")
		)
		(fp_line
			(start -0.12065 -0.2794)
			(end 0.12065 -0.2794)
			(stroke
				(width 0.1)
				(type default)
			)
			(layer "F.Fab")
		)
		(fp_line
			(start -0.12065 0.2794)
			(end -0.12065 0.3048)
			(stroke
				(width 0.1)
				(type default)
			)
			(layer "F.Fab")
		)
		(fp_line
			(start -0.12065 0.3048)
			(end -0.67945 0.3048)
			(stroke
				(width 0.1)
				(type default)
			)
			(layer "F.Fab")
		)
		(fp_line
			(start 0.120396 0.2794)
			(end -0.12065 0.2794)
			(stroke
				(width 0.1)
				(type default)
			)
			(layer "F.Fab")
		)
		(fp_line
			(start 0.120396 0.3048)
			(end 0.120396 0.2794)
			(stroke
				(width 0.1)
				(type default)
			)
			(layer "F.Fab")
		)
		(fp_line
			(start 0.12065 -0.3048)
			(end 0.67945 -0.3048)
			(stroke
				(width 0.1)
				(type default)
			)
			(layer "F.Fab")
		)
		(fp_line
			(start 0.12065 -0.2794)
			(end 0.12065 -0.3048)
			(stroke
				(width 0.1)
				(type default)
			)
			(layer "F.Fab")
		)
		(fp_line
			(start 0.67945 -0.3048)
			(end 0.67945 0.3048)
			(stroke
				(width 0.1)
				(type default)
			)
			(layer "F.Fab")
		)
		(fp_line
			(start 0.67945 0.3048)
			(end 0.120396 0.3048)
			(stroke
				(width 0.1)
				(type default)
			)
			(layer "F.Fab")
		)
		(pad "1" smd circle
			(at -0.40005 0)
			(size 0 0)
			(layers "F.Cu" "F.Mask" "F.Paste")
			(net "FM_CPU_FBRK_DEBUG_N")
		)
		(pad "2" smd circle
			(at 0.40005 0)
			(size 0 0)
			(layers "F.Cu" "F.Mask" "F.Paste")
			(net "GND")
		)
	)
	(footprint ""
		(layer "F.Cu")
		(at 341.651082 -24.217122 -90)
		(property "Reference" "R727"
			(at 0 0 270)
			(layer "F.SilkS")
			(hide yes)
			(effects
				(font
					(size 1.27 1.27)
				)
			)
		)
		(property "Value" ""
			(at 0 0 270)
			(layer "F.Fab")
			(effects
				(font
					(size 1.27 1.27)
				)
			)
		)
		(duplicate_pad_numbers_are_jumpers no)
		(fp_line
			(start -0.7874 0.4064)
			(end -0.7874 -0.4064)
			(stroke
				(width 0.1524)
				(type default)
			)
			(layer "F.SilkS")
		)
		(fp_line
			(start 0.7874 0.4064)
			(end -0.7874 0.4064)
			(stroke
				(width 0.1524)
				(type default)
			)
			(layer "F.SilkS")
		)
		(fp_line
			(start -0.7874 -0.4064)
			(end 0.7874 -0.4064)
			(stroke
				(width 0.1524)
				(type default)
			)
			(layer "F.SilkS")
		)
		(fp_line
			(start 0.7874 -0.4064)
			(end 0.7874 0.4064)
			(stroke
				(width 0.1524)
				(type default)
			)
			(layer "F.SilkS")
		)
		(fp_line
			(start -0.67945 0.3048)
			(end -0.67945 -0.305054)
			(stroke
				(width 0.1)
				(type default)
			)
			(layer "F.Fab")
		)
		(fp_line
			(start -0.12065 0.3048)
			(end -0.67945 0.3048)
			(stroke
				(width 0.1)
				(type default)
			)
			(layer "F.Fab")
		)
		(fp_line
			(start 0.120396 0.3048)
			(end 0.120396 0.2794)
			(stroke
				(width 0.1)
				(type default)
			)
			(layer "F.Fab")
		)
		(fp_line
			(start 0.67945 0.3048)
			(end 0.120396 0.3048)
			(stroke
				(width 0.1)
				(type default)
			)
			(layer "F.Fab")
		)
		(fp_line
			(start -0.12065 0.2794)
			(end -0.12065 0.3048)
			(stroke
				(width 0.1)
				(type default)
			)
			(layer "F.Fab")
		)
		(fp_line
			(start 0.120396 0.2794)
			(end -0.12065 0.2794)
			(stroke
				(width 0.1)
				(type default)
			)
			(layer "F.Fab")
		)
		(fp_line
			(start -0.12065 -0.2794)
			(end 0.12065 -0.2794)
			(stroke
				(width 0.1)
				(type default)
			)
			(layer "F.Fab")
		)
		(fp_line
			(start 0.12065 -0.2794)
			(end 0.12065 -0.3048)
			(stroke
				(width 0.1)
				(type default)
			)
			(layer "F.Fab")
		)
		(fp_line
			(start 0.12065 -0.3048)
			(end 0.67945 -0.3048)
			(stroke
				(width 0.1)
				(type default)
			)
			(layer "F.Fab")
		)
		(fp_line
			(start 0.67945 -0.3048)
			(end 0.67945 0.3048)
			(stroke
				(width 0.1)
				(type default)
			)
			(layer "F.Fab")
		)
		(fp_line
			(start -0.67945 -0.305054)
			(end -0.12065 -0.305054)
			(stroke
				(width 0.1)
				(type default)
			)
			(layer "F.Fab")
		)
		(fp_line
			(start -0.12065 -0.305054)
			(end -0.12065 -0.2794)
			(stroke
				(width 0.1)
				(type default)
			)
			(layer "F.Fab")
		)
		(pad "1" smd circle
			(at -0.40005 0 270)
			(size 0 0)
			(layers "F.Cu" "F.Mask" "F.Paste")
			(net "PU_OC4_USB_N")
		)
		(pad "2" smd circle
			(at 0.40005 0 270)
			(size 0 0)
			(layers "F.Cu" "F.Mask" "F.Paste")
			(net "P3V3_AUX")
		)
	)
)
